FILE_TYPE=LIBRARY_PARTS;
primitive 'RAA2213404GNPHB0';
  pin
    'PWM':
      PIN_NUMBER='(21)';
      INPUT_LOAD='(-0.01,0.01)';
    'REFIN':
      PIN_NUMBER='(24)';
      INPUT_LOAD='(-0.01,0.01)';
    'GND2':
      PIN_NUMBER='(23)';
      PINUSE='POWER';
      NO_LOAD_CHECK='Both';
      NO_IO_CHECK='Both';
      NO_ASSERT_CHECK='TRUE';
      NO_DIR_CHECK='TRUE';
      ALLOW_CONNECT='TRUE';
    'BOOT':
      PIN_NUMBER='(20)';
      PINUSE='POWER';
      NO_LOAD_CHECK='Both';
      NO_IO_CHECK='Both';
      NO_ASSERT_CHECK='TRUE';
      NO_DIR_CHECK='TRUE';
      ALLOW_CONNECT='TRUE';
    'VIN':
      PIN_NUMBER='(16_18-28)';
      PINUSE='POWER';
      NO_LOAD_CHECK='Both';
      NO_IO_CHECK='Both';
      NO_ASSERT_CHECK='TRUE';
      NO_DIR_CHECK='TRUE';
      ALLOW_CONNECT='TRUE';
    'PHASE':
      PIN_NUMBER='(19)';
      PINUSE='POWER';
      NO_LOAD_CHECK='Both';
      NO_IO_CHECK='Both';
      NO_ASSERT_CHECK='TRUE';
      NO_DIR_CHECK='TRUE';
      ALLOW_CONNECT='TRUE';
    'VCC':
      PIN_NUMBER='(4)';
      PINUSE='POWER';
      NO_LOAD_CHECK='Both';
      NO_IO_CHECK='Both';
      NO_ASSERT_CHECK='TRUE';
      NO_DIR_CHECK='TRUE';
      ALLOW_CONNECT='TRUE';
    'TMON':
      PIN_NUMBER='(1)';
      OUTPUT_LOAD='(1.0,-1.0)';
    'IMON':
      PIN_NUMBER='(25)';
      OUTPUT_LOAD='(1.0,-1.0)';
    'GND1':
      PIN_NUMBER='(6_7-13_15-29)';
      PINUSE='POWER';
      NO_LOAD_CHECK='Both';
      NO_IO_CHECK='Both';
      NO_ASSERT_CHECK='TRUE';
      NO_DIR_CHECK='TRUE';
      ALLOW_CONNECT='TRUE';
    'GL2':
      PIN_NUMBER='(27)';
      OUTPUT_LOAD='(1.0,-1.0)';
    'SW':
      PIN_NUMBER='(8_12)';
      OUTPUT_LOAD='(1.0,-1.0)';
    'FAULT#':
      PIN_NUMBER='(2)';
      OUTPUT_TYPE='(OC,AND)';
      OUTPUT_LOAD='(1.0,*)';
    'GND3':
      PIN_NUMBER='(26)';
      PINUSE='POWER';
      NO_LOAD_CHECK='Both';
      NO_IO_CHECK='Both';
      NO_ASSERT_CHECK='TRUE';
      NO_DIR_CHECK='TRUE';
      ALLOW_CONNECT='TRUE';
    'NC1':
      PIN_NUMBER='(22)';
      OUTPUT_TYPE='(TS,TS)';
      INPUT_LOAD='(-0.01,0.01)';
      OUTPUT_LOAD='(1.0,-1.0)';
    'GL1':
      PIN_NUMBER='(5)';
      OUTPUT_LOAD='(1.0,-1.0)';
    'LGCTRL':
      PIN_NUMBER='(3)';
      INPUT_LOAD='(-0.01,0.01)';
  end_pin;
  body
    PART_NAME='RAA2213404GNPHB0';
    BODY_NAME='RAA2213404GNPHB0';
    PHYS_DES_PREFIX='U';
    CLASS='IC';
  end_body;
end_primitive;

END.
